(kicad_pcb
	(version 20241229)
	(generator "pcbnew")
	(generator_version "9.0")
	(general
		(thickness 1.294)
		(legacy_teardrops no)
	)
	(paper "A3")
	(title_block
		(title "Kintex 410T devboard")
		(date "2024-04-03")
		(rev "1.1.2")
		(comment 9 "footprint 170 of 975 (U1), pads 297-355 of 900")
	)
	(layers
		(0 "F.Cu" mixed)
		(4 "In1.Cu" power)
		(6 "In2.Cu" power)
		(8 "In3.Cu" mixed)
		(10 "In4.Cu" power)
		(12 "In5.Cu" mixed)
		(14 "In6.Cu" power)
		(16 "In7.Cu" mixed)
		(18 "In8.Cu" power)
		(2 "B.Cu" mixed)
		(9 "F.Adhes" user "F.Adhesive")
		(11 "B.Adhes" user "B.Adhesive")
		(13 "F.Paste" user)
		(15 "B.Paste" user)
		(5 "F.SilkS" user "F.Silkscreen")
		(7 "B.SilkS" user "B.Silkscreen")
		(1 "F.Mask" user)
		(3 "B.Mask" user)
		(17 "Dwgs.User" user "User.Drawings")
		(19 "Cmts.User" user "User.Comments")
		(21 "Eco1.User" user "User.Eco1")
		(23 "Eco2.User" user "User.Eco2")
		(25 "Edge.Cuts" user)
		(27 "Margin" user)
		(31 "F.CrtYd" user "F.Courtyard")
		(29 "B.CrtYd" user "B.Courtyard")
		(35 "F.Fab" user)
		(33 "B.Fab" user)
	)
	(footprint "antmicro-footprints:BGA-900_31x31mm_Layout30x30_P1x1mm_FFG900"
		(locked yes)
		(layer "F.Cu")
		(at 200 130)
		(property "Reference" "U1"
			(at -15.74 -15.78 0)
			(layer "F.SilkS")
			(effects
				(font
					(size 0.7 0.7)
					(thickness 0.15)
				)
				(justify left bottom)
			)
		)
		(property "Value" "XC7K410T-2FFG900I"
			(at -4.436 17.635 0)
			(layer "F.Fab")
			(effects
				(font
					(size 0.7 0.7)
					(thickness 0.15)
				)
				(justify left bottom)
			)
		)
		(property "Description" "FPGA, Kintex-7, MMCM, PLL, 350 I/O's, 710 MHz, 406720 Cells, 970 mV to 1.03 V, FCBGA-900"
			(at 0 0 0)
			(layer "F.Fab")
			(hide yes)
			(effects
				(font
					(size 1.27 1.27)
					(thickness 0.15)
				)
			)
		)
		(property "Author" "Antmicro"
			(at 0 0 0)
			(layer "F.Fab")
			(hide yes)
			(effects
				(font
					(size 1 1)
					(thickness 0.15)
				)
			)
		)
		(property "License" "Apache-2.0"
			(at 0 0 0)
			(layer "F.Fab")
			(hide yes)
			(effects
				(font
					(size 1 1)
					(thickness 0.15)
				)
			)
		)
		(property "MPN" "XC7K410T-2FFG900I"
			(at 0 0 0)
			(layer "F.Fab")
			(hide yes)
			(effects
				(font
					(size 1 1)
					(thickness 0.15)
				)
			)
		)
		(property "Manufacturer" "AMD-Xilinx"
			(at 0 0 0)
			(layer "F.Fab")
			(hide yes)
			(effects
				(font
					(size 1 1)
					(thickness 0.15)
				)
			)
		)
		(sheetname "FPGA supply")
		(sheetfile "fpga-supply.kicad_sch")
		(attr smd)
		(pad "AJ27" smd circle
			(at 11.5 13.5)
			(size 0.5 0.5)
			(property pad_prop_bga)
			(layers "F.Cu" "F.Mask" "F.Paste")
			(net 778 "unconnected-(U1A-IO_L20P_T3_13-PadAJ27)")
			(pinfunction "IO_L20P_T3_13")
			(pintype "bidirectional+no_connect")
			(die_length 19.574)
			(solder_mask_margin 0.02)
		)
		(pad "AJ28" smd circle
			(at 12.5 13.5)
			(size 0.5 0.5)
			(property pad_prop_bga)
			(layers "F.Cu" "F.Mask" "F.Paste")
			(net 461 "/FPGA Bank 12 & 13/PMOD_A.IO4")
			(pinfunction "IO_L17P_T2_13")
			(pintype "bidirectional")
			(die_length 19.784)
			(solder_mask_margin 0.02)
		)
		(pad "AJ29" smd circle
			(at 13.5 13.5)
			(size 0.5 0.5)
			(property pad_prop_bga)
			(layers "F.Cu" "F.Mask" "F.Paste")
			(net 439 "/FPGA Bank 12 & 13/PMOD_A.IO10")
			(pinfunction "IO_L17N_T2_13")
			(pintype "bidirectional")
			(die_length 19.876)
			(solder_mask_margin 0.02)
		)
		(pad "AJ30" smd circle
			(at 14.5 13.5)
			(size 0.5 0.5)
			(property pad_prop_bga)
			(layers "F.Cu" "F.Mask" "F.Paste")
			(net 1 "GND")
			(pinfunction "GND")
			(pintype "passive")
			(solder_mask_margin 0.02)
		)
		(pad "AK1" smd circle
			(at -14.5 14.5)
			(size 0.5 0.5)
			(property pad_prop_bga)
			(layers "F.Cu" "F.Mask" "F.Paste")
			(net 784 "unconnected-(U1E-IO_L17N_T2_34-PadAK1)")
			(pinfunction "IO_L17N_T2_34")
			(pintype "bidirectional+no_connect")
			(die_length 24.656)
			(solder_mask_margin 0.02)
		)
		(pad "AK2" smd circle
			(at -13.5 14.5)
			(size 0.5 0.5)
			(property pad_prop_bga)
			(layers "F.Cu" "F.Mask" "F.Paste")
			(net 25 "+1V35")
			(pinfunction "VCCO_34")
			(pintype "passive")
			(solder_mask_margin 0.02)
		)
		(pad "AK3" smd circle
			(at -12.5 14.5)
			(size 0.5 0.5)
			(property pad_prop_bga)
			(layers "F.Cu" "F.Mask" "F.Paste")
			(net 786 "unconnected-(U1E-IO_L18N_T2_34-PadAK3)")
			(pinfunction "IO_L18N_T2_34")
			(pintype "bidirectional+no_connect")
			(die_length 23.037)
			(solder_mask_margin 0.02)
		)
		(pad "AK4" smd circle
			(at -11.5 14.5)
			(size 0.5 0.5)
			(property pad_prop_bga)
			(layers "F.Cu" "F.Mask" "F.Paste")
			(net 660 "/DRAM + SRAM/DDR.DQ6")
			(pinfunction "IO_L24N_T3_34")
			(pintype "bidirectional")
			(die_length 23.568)
			(solder_mask_margin 0.02)
		)
		(pad "AK5" smd circle
			(at -10.5 14.5)
			(size 0.5 0.5)
			(property pad_prop_bga)
			(layers "F.Cu" "F.Mask" "F.Paste")
			(net 661 "/DRAM + SRAM/DDR.DQ0")
			(pinfunction "IO_L24P_T3_34")
			(pintype "bidirectional")
			(die_length 22.516)
			(solder_mask_margin 0.02)
		)
		(pad "AK6" smd circle
			(at -9.5 14.5)
			(size 0.5 0.5)
			(property pad_prop_bga)
			(layers "F.Cu" "F.Mask" "F.Paste")
			(net 662 "/DRAM + SRAM/DDR.DQ2")
			(pinfunction "IO_L22N_T3_34")
			(pintype "bidirectional")
			(die_length 21.012)
			(solder_mask_margin 0.02)
		)
		(pad "AK7" smd circle
			(at -8.5 14.5)
			(size 0.5 0.5)
			(property pad_prop_bga)
			(layers "F.Cu" "F.Mask" "F.Paste")
			(net 1 "GND")
			(pinfunction "GND")
			(pintype "passive")
			(solder_mask_margin 0.02)
		)
		(pad "AK8" smd circle
			(at -7.5 14.5)
			(size 0.5 0.5)
			(property pad_prop_bga)
			(layers "F.Cu" "F.Mask" "F.Paste")
			(net 663 "/DRAM + SRAM/DDR.DQ1")
			(pinfunction "IO_L23N_T3_34")
			(pintype "bidirectional")
			(die_length 21.371)
			(solder_mask_margin 0.02)
		)
		(pad "AK9" smd circle
			(at -6.5 14.5)
			(size 0.5 0.5)
			(property pad_prop_bga)
			(layers "F.Cu" "F.Mask" "F.Paste")
			(net 512 "unconnected-(U1E-IO_L15N_T2_DQS_33-PadAK9)")
			(pinfunction "IO_L15N_T2_DQS_33")
			(pintype "bidirectional+no_connect")
			(die_length 18.854)
			(solder_mask_margin 0.02)
		)
		(pad "AK10" smd circle
			(at -5.5 14.5)
			(size 0.5 0.5)
			(property pad_prop_bga)
			(layers "F.Cu" "F.Mask" "F.Paste")
			(net 518 "unconnected-(U1E-IO_L17N_T2_33-PadAK10)")
			(pinfunction "IO_L17N_T2_33")
			(pintype "bidirectional+no_connect")
			(die_length 19.289)
			(solder_mask_margin 0.02)
		)
		(pad "AK11" smd circle
			(at -4.5 14.5)
			(size 0.5 0.5)
			(property pad_prop_bga)
			(layers "F.Cu" "F.Mask" "F.Paste")
			(net 625 "unconnected-(U1E-IO_L17P_T2_33-PadAK11)")
			(pinfunction "IO_L17P_T2_33")
			(pintype "bidirectional+no_connect")
			(die_length 20.52)
			(solder_mask_margin 0.02)
		)
		(pad "AK12" smd circle
			(at -3.5 14.5)
			(size 0.5 0.5)
			(property pad_prop_bga)
			(layers "F.Cu" "F.Mask" "F.Paste")
			(net 26 "+1V8")
			(pinfunction "VCCO_33")
			(pintype "passive")
			(solder_mask_margin 0.02)
		)
		(pad "AK13" smd circle
			(at -2.5 14.5)
			(size 0.5 0.5)
			(property pad_prop_bga)
			(layers "F.Cu" "F.Mask" "F.Paste")
			(net 411 "/FPGA Bank 33 & 34/USR_FLASH_0.DQ1")
			(pinfunction "IO_L20N_T3_33")
			(pintype "bidirectional")
			(die_length 21.609)
			(solder_mask_margin 0.02)
		)
		(pad "AK14" smd circle
			(at -1.5 14.5)
			(size 0.5 0.5)
			(property pad_prop_bga)
			(layers "F.Cu" "F.Mask" "F.Paste")
			(net 395 "/FPGA Bank 33 & 34/SD_CARD.DAT0")
			(pinfunction "IO_L20P_T3_33")
			(pintype "bidirectional")
			(die_length 23.027)
			(solder_mask_margin 0.02)
		)
		(pad "AK15" smd circle
			(at -0.5 14.5)
			(size 0.5 0.5)
			(property pad_prop_bga)
			(layers "F.Cu" "F.Mask" "F.Paste")
			(net 788 "unconnected-(U1D-IO_L1N_T0_32-PadAK15)")
			(pinfunction "IO_L1N_T0_32")
			(pintype "bidirectional+no_connect")
			(die_length 21.665)
			(solder_mask_margin 0.02)
		)
		(pad "AK16" smd circle
			(at 0.5 14.5)
			(size 0.5 0.5)
			(property pad_prop_bga)
			(layers "F.Cu" "F.Mask" "F.Paste")
			(net 796 "unconnected-(U1D-IO_L1P_T0_32-PadAK16)")
			(pinfunction "IO_L1P_T0_32")
			(pintype "bidirectional+no_connect")
			(die_length 22.612)
			(solder_mask_margin 0.02)
		)
		(pad "AK17" smd circle
			(at 1.5 14.5)
			(size 0.5 0.5)
			(property pad_prop_bga)
			(layers "F.Cu" "F.Mask" "F.Paste")
			(net 1 "GND")
			(pinfunction "GND")
			(pintype "passive")
			(solder_mask_margin 0.02)
		)
		(pad "AK18" smd circle
			(at 2.5 14.5)
			(size 0.5 0.5)
			(property pad_prop_bga)
			(layers "F.Cu" "F.Mask" "F.Paste")
			(net 818 "unconnected-(U1D-IO_L9N_T1_DQS_32-PadAK18)")
			(pinfunction "IO_L9N_T1_DQS_32")
			(pintype "bidirectional+no_connect")
			(die_length 22.005)
			(solder_mask_margin 0.02)
		)
		(pad "AK19" smd circle
			(at 3.5 14.5)
			(size 0.5 0.5)
			(property pad_prop_bga)
			(layers "F.Cu" "F.Mask" "F.Paste")
			(net 819 "unconnected-(U1D-IO_L7N_T1_32-PadAK19)")
			(pinfunction "IO_L7N_T1_32")
			(pintype "bidirectional+no_connect")
			(die_length 23.523)
			(solder_mask_margin 0.02)
		)
		(pad "AK20" smd circle
			(at 4.5 14.5)
			(size 0.5 0.5)
			(property pad_prop_bga)
			(layers "F.Cu" "F.Mask" "F.Paste")
			(net 477 "/FPGA Bank 12 & 13/CW_HEADER.TSCK")
			(pinfunction "IO_L24P_T3_12")
			(pintype "bidirectional")
			(die_length 12.709)
			(solder_mask_margin 0.02)
		)
		(pad "AK21" smd circle
			(at 5.5 14.5)
			(size 0.5 0.5)
			(property pad_prop_bga)
			(layers "F.Cu" "F.Mask" "F.Paste")
			(net 476 "/FPGA Bank 12 & 13/CW_HEADER.MOSI")
			(pinfunction "IO_L24N_T3_12")
			(pintype "bidirectional")
			(die_length 13.051)
			(solder_mask_margin 0.02)
		)
		(pad "AK22" smd circle
			(at 6.5 14.5)
			(size 0.5 0.5)
			(property pad_prop_bga)
			(layers "F.Cu" "F.Mask" "F.Paste")
			(net 24 "+3V3")
			(pinfunction "VCCO_12")
			(pintype "passive")
			(solder_mask_margin 0.02)
		)
		(pad "AK23" smd circle
			(at 7.5 14.5)
			(size 0.5 0.5)
			(property pad_prop_bga)
			(layers "F.Cu" "F.Mask" "F.Paste")
			(net 1331 "/SUP_MCU.RX0")
			(pinfunction "IO_L17P_T2_12")
			(pintype "bidirectional")
			(die_length 14.198)
			(solder_mask_margin 0.02)
		)
		(pad "AK24" smd circle
			(at 8.5 14.5)
			(size 0.5 0.5)
			(property pad_prop_bga)
			(layers "F.Cu" "F.Mask" "F.Paste")
			(net 692 "unconnected-(U1A-IO_L17N_T2_12-PadAK24)")
			(pinfunction "IO_L17N_T2_12")
			(pintype "bidirectional+no_connect")
			(die_length 14.315)
			(solder_mask_margin 0.02)
		)
		(pad "AK25" smd circle
			(at 9.5 14.5)
			(size 0.5 0.5)
			(property pad_prop_bga)
			(layers "F.Cu" "F.Mask" "F.Paste")
			(net 1371 "/SUP_MCU.A12")
			(pinfunction "IO_L15N_T2_DQS_12")
			(pintype "bidirectional")
			(die_length 14.925)
			(solder_mask_margin 0.02)
		)
		(pad "AK26" smd circle
			(at 10.5 14.5)
			(size 0.5 0.5)
			(property pad_prop_bga)
			(layers "F.Cu" "F.Mask" "F.Paste")
			(net 497 "/FPGA Bank 12 & 13/USB_USER.VDET")
			(pinfunction "IO_L24N_T3_13")
			(pintype "bidirectional")
			(die_length 18.616)
			(solder_mask_margin 0.02)
		)
		(pad "AK27" smd circle
			(at 11.5 14.5)
			(size 0.5 0.5)
			(property pad_prop_bga)
			(layers "F.Cu" "F.Mask" "F.Paste")
			(net 1 "GND")
			(pinfunction "GND")
			(pintype "passive")
			(solder_mask_margin 0.02)
		)
		(pad "AK28" smd circle
			(at 12.5 14.5)
			(size 0.5 0.5)
			(property pad_prop_bga)
			(layers "F.Cu" "F.Mask" "F.Paste")
			(net 456 "/FPGA Bank 12 & 13/PMOD_A.IO1")
			(pinfunction "IO_L20N_T3_13")
			(pintype "bidirectional")
			(die_length 20.362)
			(solder_mask_margin 0.02)
		)
		(pad "AK29" smd circle
			(at 13.5 14.5)
			(size 0.5 0.5)
			(property pad_prop_bga)
			(layers "F.Cu" "F.Mask" "F.Paste")
			(net 871 "unconnected-(U1A-IO_L15P_T2_DQS_13-PadAK29)")
			(pinfunction "IO_L15P_T2_DQS_13")
			(pintype "bidirectional+no_connect")
			(die_length 22.007)
			(solder_mask_margin 0.02)
		)
		(pad "AK30" smd circle
			(at 14.5 14.5)
			(size 0.5 0.5)
			(property pad_prop_bga)
			(layers "F.Cu" "F.Mask" "F.Paste")
			(net 1377 "/SUP_MCU.SPARE0")
			(pinfunction "IO_L15N_T2_DQS_13")
			(pintype "bidirectional")
			(die_length 21.946)
			(solder_mask_margin 0.02)
		)
		(pad "B1" smd circle
			(at -14.5 -13.5)
			(size 0.5 0.5)
			(property pad_prop_bga)
			(layers "F.Cu" "F.Mask" "F.Paste")
			(net 873 "unconnected-(U1G-MGTXTXN2_118-PadB1)")
			(pinfunction "MGTXTXN2_118")
			(pintype "bidirectional+no_connect")
			(die_length 16.521)
			(solder_mask_margin 0.02)
		)
		(pad "B2" smd circle
			(at -13.5 -13.5)
			(size 0.5 0.5)
			(property pad_prop_bga)
			(layers "F.Cu" "F.Mask" "F.Paste")
			(net 874 "unconnected-(U1G-MGTXTXP2_118-PadB2)")
			(pinfunction "MGTXTXP2_118")
			(pintype "bidirectional+no_connect")
			(die_length 16.53)
			(solder_mask_margin 0.02)
		)
		(pad "B3" smd circle
			(at -12.5 -13.5)
			(size 0.5 0.5)
			(property pad_prop_bga)
			(layers "F.Cu" "F.Mask" "F.Paste")
			(net 8 "+1V2_MGTAVTT")
			(pinfunction "MGTAVTT")
			(pintype "bidirectional")
			(solder_mask_margin 0.02)
		)
		(pad "B4" smd circle
			(at -11.5 -13.5)
			(size 0.5 0.5)
			(property pad_prop_bga)
			(layers "F.Cu" "F.Mask" "F.Paste")
			(net 1 "GND")
			(pinfunction "GND")
			(pintype "passive")
			(solder_mask_margin 0.02)
		)
		(pad "B5" smd circle
			(at -10.5 -13.5)
			(size 0.5 0.5)
			(property pad_prop_bga)
			(layers "F.Cu" "F.Mask" "F.Paste")
			(net 890 "unconnected-(U1G-MGTXRXN2_118-PadB5)")
			(pinfunction "MGTXRXN2_118")
			(pintype "bidirectional+no_connect")
			(die_length 12.709)
			(solder_mask_margin 0.02)
		)
		(pad "B6" smd circle
			(at -9.5 -13.5)
			(size 0.5 0.5)
			(property pad_prop_bga)
			(layers "F.Cu" "F.Mask" "F.Paste")
			(net 892 "unconnected-(U1G-MGTXRXP2_118-PadB6)")
			(pinfunction "MGTXRXP2_118")
			(pintype "bidirectional+no_connect")
			(die_length 12.944)
			(solder_mask_margin 0.02)
		)
		(pad "B7" smd circle
			(at -8.5 -13.5)
			(size 0.5 0.5)
			(property pad_prop_bga)
			(layers "F.Cu" "F.Mask" "F.Paste")
			(net 6 "+1V0_MGTAVCC")
			(pinfunction "MGTAVCC")
			(pintype "bidirectional")
			(solder_mask_margin 0.02)
		)
		(pad "B8" smd circle
			(at -7.5 -13.5)
			(size 0.5 0.5)
			(property pad_prop_bga)
			(layers "F.Cu" "F.Mask" "F.Paste")
			(net 1 "GND")
			(pinfunction "GND")
			(pintype "passive")
			(solder_mask_margin 0.02)
		)
		(pad "B9" smd circle
			(at -6.5 -13.5)
			(size 0.5 0.5)
			(property pad_prop_bga)
			(layers "F.Cu" "F.Mask" "F.Paste")
			(net 1 "GND")
			(pinfunction "GND")
			(pintype "passive")
			(solder_mask_margin 0.02)
		)
		(pad "B10" smd circle
			(at -5.5 -13.5)
			(size 0.5 0.5)
			(property pad_prop_bga)
			(layers "F.Cu" "F.Mask" "F.Paste")
			(net 56 "/FPGA Bank 14 & 15/SYSTEM_FLASH.CLK")
			(pinfunction "CCLK_0")
			(pintype "bidirectional")
			(die_length 29.155)
			(solder_mask_margin 0.02)
		)
		(pad "B11" smd circle
			(at -4.5 -13.5)
			(size 0.5 0.5)
			(property pad_prop_bga)
			(layers "F.Cu" "F.Mask" "F.Paste")
			(net 1 "GND")
			(pinfunction "GND")
			(pintype "passive")
			(solder_mask_margin 0.02)
		)
		(pad "B12" smd circle
			(at -3.5 -13.5)
			(size 0.5 0.5)
			(property pad_prop_bga)
			(layers "F.Cu" "F.Mask" "F.Paste")
			(net 641 "/FMC+ HSPC/FMC.IO15_N")
			(pinfunction "IO_L15N_T2_DQS_18")
			(pintype "bidirectional")
			(die_length 25.173)
			(solder_mask_margin 0.02)
		)
		(pad "B13" smd circle
			(at -2.5 -13.5)
			(size 0.5 0.5)
			(property pad_prop_bga)
			(layers "F.Cu" "F.Mask" "F.Paste")
			(net 642 "/FMC+ HSPC/FMC.IO22_P")
			(pinfunction "IO_L22P_T3_18")
			(pintype "bidirectional")
			(die_length 24.88)
			(solder_mask_margin 0.02)
		)
		(pad "B14" smd circle
			(at -1.5 -13.5)
			(size 0.5 0.5)
			(property pad_prop_bga)
			(layers "F.Cu" "F.Mask" "F.Paste")
			(net 350 "/FMC+ HSPC/FMC.IO24_P")
			(pinfunction "IO_L24P_T3_18")
			(pintype "bidirectional")
			(die_length 24.532)
			(solder_mask_margin 0.02)
		)
		(pad "B15" smd circle
			(at -0.5 -13.5)
			(size 0.5 0.5)
			(property pad_prop_bga)
			(layers "F.Cu" "F.Mask" "F.Paste")
			(net 444 "/FMC+ HSPC/FMC.IO23_N")
			(pinfunction "IO_L23N_T3_18")
			(pintype "bidirectional")
			(die_length 22.701)
			(solder_mask_margin 0.02)
		)
		(pad "B16" smd circle
			(at 0.5 -13.5)
			(size 0.5 0.5)
			(property pad_prop_bga)
			(layers "F.Cu" "F.Mask" "F.Paste")
			(net 24 "+3V3")
			(pinfunction "VCCO_17")
			(pintype "passive")
			(solder_mask_margin 0.02)
		)
		(pad "B17" smd circle
			(at 1.5 -13.5)
			(size 0.5 0.5)
			(property pad_prop_bga)
			(layers "F.Cu" "F.Mask" "F.Paste")
			(net 893 "/FPGA Bank 12 & 13/USB_HOST.~{CS}")
			(pinfunction "IO_L17N_T2_17")
			(pintype "bidirectional")
			(die_length 23.879)
			(solder_mask_margin 0.02)
		)
		(pad "B18" smd circle
			(at 2.5 -13.5)
			(size 0.5 0.5)
			(property pad_prop_bga)
			(layers "F.Cu" "F.Mask" "F.Paste")
			(net 495 "/FPGA Bank 12 & 13/USB_HOST.INT")
			(pinfunction "IO_L22P_T3_17")
			(pintype "bidirectional")
			(die_length 24.881)
			(solder_mask_margin 0.02)
		)
		(pad "B19" smd circle
			(at 3.5 -13.5)
			(size 0.5 0.5)
			(property pad_prop_bga)
			(layers "F.Cu" "F.Mask" "F.Paste")
			(net 525 "/FPGA Bank 16 & 17/HDMI.D2_N")
			(pinfunction "IO_L24N_T3_17")
			(pintype "bidirectional")
			(die_length 25.226)
			(solder_mask_margin 0.02)
		)
		(pad "B20" smd circle
			(at 4.5 -13.5)
			(size 0.5 0.5)
			(property pad_prop_bga)
			(layers "F.Cu" "F.Mask" "F.Paste")
			(net 527 "/FPGA Bank 16 & 17/HDMI.D1_N")
			(pinfunction "IO_L19N_T3_VREF_17")
			(pintype "bidirectional")
			(die_length 21.681)
			(solder_mask_margin 0.02)
		)
		(pad "B21" smd circle
			(at 5.5 -13.5)
			(size 0.5 0.5)
			(property pad_prop_bga)
			(layers "F.Cu" "F.Mask" "F.Paste")
			(net 1 "GND")
			(pinfunction "GND")
			(pintype "passive")
			(solder_mask_margin 0.02)
		)
		(pad "B22" smd circle
			(at 6.5 -13.5)
			(size 0.5 0.5)
			(property pad_prop_bga)
			(layers "F.Cu" "F.Mask" "F.Paste")
			(net 530 "/FPGA Bank 16 & 17/HDMI.CLK_P")
			(pinfunction "IO_L23P_T3_17")
			(pintype "bidirectional")
			(die_length 21.288)
			(solder_mask_margin 0.02)
		)
		(pad "B23" smd circle
			(at 7.5 -13.5)
			(size 0.5 0.5)
			(property pad_prop_bga)
			(layers "F.Cu" "F.Mask" "F.Paste")
			(net 780 "unconnected-(U1C-IO_L1P_T0_16-PadB23)")
			(pinfunction "IO_L1P_T0_16")
			(pintype "bidirectional+no_connect")
			(die_length 20.406)
			(solder_mask_margin 0.02)
		)
		(pad "B24" smd circle
			(at 8.5 -13.5)
			(size 0.5 0.5)
			(property pad_prop_bga)
			(layers "F.Cu" "F.Mask" "F.Paste")
			(net 1278 "/USER_IO.B16")
			(pinfunction "IO_L8N_T1_16")
			(pintype "bidirectional")
			(die_length 22.133)
			(solder_mask_margin 0.02)
		)
		(pad "B25" smd circle
			(at 9.5 -13.5)
			(size 0.5 0.5)
			(property pad_prop_bga)
			(layers "F.Cu" "F.Mask" "F.Paste")
			(net 1286 "/USER_IO.B26")
			(pinfunction "IO_L12N_T1_MRCC_16")
			(pintype "bidirectional")
			(die_length 22.219)
			(solder_mask_margin 0.02)
		)
	)
)
